(kicad_pcb
	(version 20260206)
	(generator "pcbnew")
	(generator_version "10.0")
	(general
		(thickness 1.6)
		(legacy_teardrops no)
	)
	(paper "A4")
	(title_block
		(title "timecard-production-celestica-r4006 — R4006-B0001-02_R01.brd")
		(comment 1 "Time Appliance Project (Time Card) / footprints 717-721 of 1113")
	)
	(layers
		(0 "F.Cu" signal "TOP")
		(4 "In1.Cu" signal "L02_GND1")
		(6 "In2.Cu" signal "L03_SIG1")
		(8 "In3.Cu" signal "L04_GND2")
		(10 "In4.Cu" signal "L05_VCC1")
		(12 "In5.Cu" signal "L06_VCC2")
		(14 "In6.Cu" signal "L07_GND3")
		(16 "In7.Cu" signal "L08_SIG2")
		(18 "In8.Cu" signal "L09_GND4")
		(2 "B.Cu" signal "BOTTOM")
		(9 "F.Adhes" user "F.Adhesive")
		(11 "B.Adhes" user "B.Adhesive")
		(13 "F.Paste" user "Package Geometry/Pastemask Top")
		(15 "B.Paste" user "Package Geometry/Pastemask Bottom")
		(5 "F.SilkS" user "Ref Des/Silkscreen Top")
		(7 "B.SilkS" user "Ref Des/Silkscreen Bottom")
		(1 "F.Mask" user "Board Geometry/Soldermask Top")
		(3 "B.Mask" user "Board Geometry/Soldermask Bottom")
		(17 "Dwgs.User" user "User.Drawings")
		(19 "Cmts.User" user "User.Comments")
		(21 "Eco1.User" user "User.Eco1")
		(23 "Eco2.User" user "User.Eco2")
		(25 "Edge.Cuts" user "Board Geometry/Outline")
		(27 "Margin" user)
		(31 "F.CrtYd" user "Package Geometry/Place Bound Top")
		(29 "B.CrtYd" user "Package Geometry/Place Bound Bottom")
		(35 "F.Fab" user "Ref Des/Assembly Top")
		(33 "B.Fab" user "Ref Des/Assembly Bottom")
	)
	(footprint ""
		(layer "B.Cu")
		(at 83.2358 -83.693 180)
		(property "Reference" "R153"
			(at 0.6858 5.67563 0)
			(unlocked yes)
			(layer "B.SilkS")
			(effects
				(font
					(size 0.7874 0.5842)
					(thickness 0.1524)
				)
				(justify mirror)
			)
		)
		(property "Value" "VAL*"
			(at -0.02032 2.13233 180)
			(unlocked yes)
			(layer "B.Fab")
			(hide yes)
			(effects
				(font
					(size 0.7874 0.5842)
					(thickness 0.1524)
				)
				(justify mirror)
			)
		)
		(property "Tolerance" "TOL*"
			(at -0.044704 3.05435 180)
			(unlocked yes)
			(layer "Cmts.User")
			(hide yes)
			(effects
				(font
					(size 0.7874 0.5842)
					(thickness 0.1524)
				)
				(justify mirror)
			)
		)
		(property "User Part Number" "PARTNUM*"
			(at -0.02032 4.024884 180)
			(unlocked yes)
			(layer "Cmts.User")
			(hide yes)
			(effects
				(font
					(size 0.7874 0.5842)
					(thickness 0.1524)
				)
				(justify mirror)
			)
		)
		(property "Device Type" "RESISTOR-G155-14701-01,4.7KOHMA"
			(at -0.008382 1.210564 180)
			(unlocked yes)
			(layer "B.Fab")
			(hide yes)
			(effects
				(font
					(size 0.7874 0.5842)
					(thickness 0.1524)
				)
				(justify mirror)
			)
		)
		(duplicate_pad_numbers_are_jumpers no)
		(fp_line
			(start 1.143 0.5588)
			(end -1.143 0.5588)
			(stroke
				(width 0.1)
				(type default)
			)
			(layer "B.SilkS")
		)
		(fp_line
			(start 1.143 -0.5588)
			(end 1.143 0.5588)
			(stroke
				(width 0.1)
				(type default)
			)
			(layer "B.SilkS")
		)
		(fp_line
			(start -1.143 0.5588)
			(end -1.143 -0.5588)
			(stroke
				(width 0.1)
				(type default)
			)
			(layer "B.SilkS")
		)
		(fp_line
			(start -1.143 -0.5588)
			(end 1.143 -0.5588)
			(stroke
				(width 0.1)
				(type default)
			)
			(layer "B.SilkS")
		)
		(fp_rect
			(start -1.143 0.5588)
			(end 1.143 -0.5588)
			(stroke
				(width 0)
				(type default)
			)
			(fill no)
			(layer "B.CrtYd")
		)
		(fp_line
			(start 0.508 0.3048)
			(end -0.508 0.3048)
			(stroke
				(width 0.1)
				(type default)
			)
			(layer "B.Fab")
		)
		(fp_line
			(start 0.508 -0.3048)
			(end 0.508 0.3048)
			(stroke
				(width 0.1)
				(type default)
			)
			(layer "B.Fab")
		)
		(fp_line
			(start -0.508 0.3048)
			(end -0.508 -0.3048)
			(stroke
				(width 0.1)
				(type default)
			)
			(layer "B.Fab")
		)
		(fp_line
			(start -0.508 -0.3048)
			(end 0.508 -0.3048)
			(stroke
				(width 0.1)
				(type default)
			)
			(layer "B.Fab")
		)
		(pad "1" smd rect
			(at 0.5334 0)
			(size 0.7112 0.6096)
			(layers "B.Cu" "B.Mask" "B.Paste")
			(net "SG")
		)
		(pad "2" smd rect
			(at -0.5334 0)
			(size 0.7112 0.6096)
			(layers "B.Cu" "B.Mask" "B.Paste")
			(net "UNNAMED_5_PCA9546APWTSSOP16_I_1")
		)
		(zone
			(layer "B.Cu")
			(hatch none 0.5)
			(connect_pads
				(clearance 0)
			)
			(min_thickness 0.25)
			(keepout
				(tracks allowed)
				(vias not_allowed)
				(pads allowed)
				(copperpour not_allowed)
				(footprints allowed)
			)
			(placement
				(enabled no)
				(sheetname "")
			)
			(fill
				(thermal_gap 0.5)
				(thermal_bridge_width 0.5)
				(island_removal_mode 0)
			)
			(polygon
				(pts
					(xy 83.312 -83.9978) (xy 83.1596 -83.9978) (xy 83.1596 -83.3882) (xy 83.312 -83.3882)
				)
			)
		)
	)
	(footprint ""
		(layer "B.Cu")
		(at 118.364 -44.577)
		(property "Reference" "R501"
			(at 2.286 0.92075 0)
			(unlocked yes)
			(layer "B.SilkS")
			(effects
				(font
					(size 0.635 0.4064)
					(thickness 0.1524)
				)
				(justify mirror)
			)
		)
		(property "Value" "VAL*"
			(at -0.02032 2.13233 0)
			(unlocked yes)
			(layer "B.Fab")
			(hide yes)
			(effects
				(font
					(size 0.7874 0.5842)
					(thickness 0.1524)
				)
				(justify mirror)
			)
		)
		(property "Tolerance" "TOL*"
			(at -0.044704 3.05435 0)
			(unlocked yes)
			(layer "Cmts.User")
			(hide yes)
			(effects
				(font
					(size 0.7874 0.5842)
					(thickness 0.1524)
				)
				(justify mirror)
			)
		)
		(property "User Part Number" "PARTNUM*"
			(at -0.02032 4.024884 0)
			(unlocked yes)
			(layer "Cmts.User")
			(hide yes)
			(effects
				(font
					(size 0.7874 0.5842)
					(thickness 0.1524)
				)
				(justify mirror)
			)
		)
		(property "Device Type" "RESISTOR-G155-14701-01,4.7KOHMA"
			(at -0.008382 1.210564 0)
			(unlocked yes)
			(layer "B.Fab")
			(hide yes)
			(effects
				(font
					(size 0.7874 0.5842)
					(thickness 0.1524)
				)
				(justify mirror)
			)
		)
		(duplicate_pad_numbers_are_jumpers no)
		(fp_line
			(start -1.143 -0.5588)
			(end 1.143 -0.5588)
			(stroke
				(width 0.1)
				(type default)
			)
			(layer "B.SilkS")
		)
		(fp_line
			(start -1.143 0.5588)
			(end -1.143 -0.5588)
			(stroke
				(width 0.1)
				(type default)
			)
			(layer "B.SilkS")
		)
		(fp_line
			(start 1.143 -0.5588)
			(end 1.143 0.5588)
			(stroke
				(width 0.1)
				(type default)
			)
			(layer "B.SilkS")
		)
		(fp_line
			(start 1.143 0.5588)
			(end -1.143 0.5588)
			(stroke
				(width 0.1)
				(type default)
			)
			(layer "B.SilkS")
		)
		(fp_poly
			(pts
				(xy 1.143 0.5588) (xy -1.143 0.5588) (xy -1.143 -0.5588) (xy 1.143 -0.5588)
			)
			(stroke
				(width 0)
				(type default)
			)
			(fill no)
			(layer "B.CrtYd")
		)
		(fp_line
			(start -0.508 -0.3048)
			(end 0.508 -0.3048)
			(stroke
				(width 0.1)
				(type default)
			)
			(layer "B.Fab")
		)
		(fp_line
			(start -0.508 0.3048)
			(end -0.508 -0.3048)
			(stroke
				(width 0.1)
				(type default)
			)
			(layer "B.Fab")
		)
		(fp_line
			(start 0.508 -0.3048)
			(end 0.508 0.3048)
			(stroke
				(width 0.1)
				(type default)
			)
			(layer "B.Fab")
		)
		(fp_line
			(start 0.508 0.3048)
			(end -0.508 0.3048)
			(stroke
				(width 0.1)
				(type default)
			)
			(layer "B.Fab")
		)
		(pad "1" smd rect
			(at 0.5334 0 180)
			(size 0.7112 0.6096)
			(layers "B.Cu" "B.Mask" "B.Paste")
			(net "SG")
		)
		(pad "2" smd rect
			(at -0.5334 0 180)
			(size 0.7112 0.6096)
			(layers "B.Cu" "B.Mask" "B.Paste")
			(net "ANT4_IN")
		)
		(zone
			(layer "B.Cu")
			(hatch none 0.5)
			(connect_pads
				(clearance 0)
			)
			(min_thickness 0.25)
			(keepout
				(tracks allowed)
				(vias not_allowed)
				(pads allowed)
				(copperpour not_allowed)
				(footprints allowed)
			)
			(placement
				(enabled no)
				(sheetname "")
			)
			(fill
				(thermal_gap 0.5)
				(thermal_bridge_width 0.5)
				(island_removal_mode 0)
			)
			(polygon
				(pts
					(xy 118.4402 -44.2722) (xy 118.4402 -44.8818) (xy 118.2878 -44.8818) (xy 118.2878 -44.2722)
				)
			)
		)
		(zone
			(layer "B.Cu")
			(hatch none 0.5)
			(connect_pads
				(clearance 0)
			)
			(min_thickness 0.25)
			(keepout
				(tracks not_allowed)
				(vias allowed)
				(pads allowed)
				(copperpour not_allowed)
				(footprints allowed)
			)
			(placement
				(enabled no)
				(sheetname "")
			)
			(fill
				(thermal_gap 0.5)
				(thermal_bridge_width 0.5)
				(island_removal_mode 0)
			)
			(polygon
				(pts
					(xy 118.4402 -44.2722) (xy 118.4402 -44.8818) (xy 118.2878 -44.8818) (xy 118.2878 -44.2722)
				)
			)
		)
	)
	(footprint ""
		(layer "B.Cu")
		(at 157.734 -50.513996 90)
		(property "Reference" "R103"
			(at -7.874 1.35763 270)
			(unlocked yes)
			(layer "B.SilkS")
			(effects
				(font
					(size 0.7874 0.5842)
					(thickness 0.1524)
				)
				(justify mirror)
			)
		)
		(property "Value" "VAL*"
			(at -0.02032 2.13233 90)
			(unlocked yes)
			(layer "B.Fab")
			(hide yes)
			(effects
				(font
					(size 0.7874 0.5842)
					(thickness 0.1524)
				)
				(justify mirror)
			)
		)
		(property "Device Type" "RESISTOR-G155-11001-01,1KOHM,1%"
			(at -0.008382 1.210564 90)
			(unlocked yes)
			(layer "B.Fab")
			(hide yes)
			(effects
				(font
					(size 0.7874 0.5842)
					(thickness 0.1524)
				)
				(justify mirror)
			)
		)
		(property "User Part Number" "PARTNUM*"
			(at -0.02032 4.024884 90)
			(unlocked yes)
			(layer "Cmts.User")
			(hide yes)
			(effects
				(font
					(size 0.7874 0.5842)
					(thickness 0.1524)
				)
				(justify mirror)
			)
		)
		(property "Tolerance" "TOL*"
			(at -0.044704 3.05435 90)
			(unlocked yes)
			(layer "Cmts.User")
			(hide yes)
			(effects
				(font
					(size 0.7874 0.5842)
					(thickness 0.1524)
				)
				(justify mirror)
			)
		)
		(duplicate_pad_numbers_are_jumpers no)
		(fp_line
			(start 1.143 -0.5588)
			(end 1.143 0.5588)
			(stroke
				(width 0.1)
				(type default)
			)
			(layer "B.SilkS")
		)
		(fp_line
			(start -1.143 -0.5588)
			(end 1.143 -0.5588)
			(stroke
				(width 0.1)
				(type default)
			)
			(layer "B.SilkS")
		)
		(fp_line
			(start 1.143 0.5588)
			(end -1.143 0.5588)
			(stroke
				(width 0.1)
				(type default)
			)
			(layer "B.SilkS")
		)
		(fp_line
			(start -1.143 0.5588)
			(end -1.143 -0.5588)
			(stroke
				(width 0.1)
				(type default)
			)
			(layer "B.SilkS")
		)
		(fp_rect
			(start 1.143 0.5588)
			(end -1.143 -0.5588)
			(stroke
				(width 0)
				(type default)
			)
			(fill no)
			(layer "B.CrtYd")
		)
		(fp_line
			(start 0.508 -0.3048)
			(end 0.508 0.3048)
			(stroke
				(width 0.1)
				(type default)
			)
			(layer "B.Fab")
		)
		(fp_line
			(start -0.508 -0.3048)
			(end 0.508 -0.3048)
			(stroke
				(width 0.1)
				(type default)
			)
			(layer "B.Fab")
		)
		(fp_line
			(start 0.508 0.3048)
			(end -0.508 0.3048)
			(stroke
				(width 0.1)
				(type default)
			)
			(layer "B.Fab")
		)
		(fp_line
			(start -0.508 0.3048)
			(end -0.508 -0.3048)
			(stroke
				(width 0.1)
				(type default)
			)
			(layer "B.Fab")
		)
		(pad "1" smd rect
			(at 0.5334 0 270)
			(size 0.7112 0.6096)
			(layers "B.Cu" "B.Mask" "B.Paste")
			(net "UNNAMED_527_RESISTOR_I201_2")
		)
		(pad "2" smd rect
			(at -0.5334 0 270)
			(size 0.7112 0.6096)
			(layers "B.Cu" "B.Mask" "B.Paste")
			(net "SG")
		)
		(zone
			(layer "B.Cu")
			(hatch none 0.5)
			(connect_pads
				(clearance 0)
			)
			(min_thickness 0.25)
			(keepout
				(tracks allowed)
				(vias not_allowed)
				(pads allowed)
				(copperpour not_allowed)
				(footprints allowed)
			)
			(placement
				(enabled no)
				(sheetname "")
			)
			(fill
				(thermal_gap 0.5)
				(thermal_bridge_width 0.5)
				(island_removal_mode 0)
			)
			(polygon
				(pts
					(xy 158.0388 -50.590196) (xy 157.4292 -50.590196) (xy 157.4292 -50.437796) (xy 158.0388 -50.437796)
				)
			)
		)
	)
	(footprint ""
		(layer "B.Cu")
		(at 85.09 -57.277)
		(property "Reference" "R75"
			(at -0.254 -1.10363 0)
			(unlocked yes)
			(layer "B.SilkS")
			(effects
				(font
					(size 0.7874 0.5842)
					(thickness 0.1524)
				)
				(justify mirror)
			)
		)
		(property "Value" "VAL*"
			(at -0.02032 2.13233 0)
			(unlocked yes)
			(layer "B.Fab")
			(hide yes)
			(effects
				(font
					(size 0.7874 0.5842)
					(thickness 0.1524)
				)
				(justify mirror)
			)
		)
		(property "Device Type" "RESISTOR-G155-14701-01,4.7KOHMA"
			(at -0.008382 1.210564 0)
			(unlocked yes)
			(layer "B.Fab")
			(hide yes)
			(effects
				(font
					(size 0.7874 0.5842)
					(thickness 0.1524)
				)
				(justify mirror)
			)
		)
		(property "User Part Number" "PARTNUM*"
			(at -0.02032 4.024884 0)
			(unlocked yes)
			(layer "Cmts.User")
			(hide yes)
			(effects
				(font
					(size 0.7874 0.5842)
					(thickness 0.1524)
				)
				(justify mirror)
			)
		)
		(property "Tolerance" "TOL*"
			(at -0.044704 3.05435 0)
			(unlocked yes)
			(layer "Cmts.User")
			(hide yes)
			(effects
				(font
					(size 0.7874 0.5842)
					(thickness 0.1524)
				)
				(justify mirror)
			)
		)
		(duplicate_pad_numbers_are_jumpers no)
		(fp_line
			(start -1.143 -0.5588)
			(end 1.143 -0.5588)
			(stroke
				(width 0.1)
				(type default)
			)
			(layer "B.SilkS")
		)
		(fp_line
			(start -1.143 0.5588)
			(end -1.143 -0.5588)
			(stroke
				(width 0.1)
				(type default)
			)
			(layer "B.SilkS")
		)
		(fp_line
			(start 1.143 -0.5588)
			(end 1.143 0.5588)
			(stroke
				(width 0.1)
				(type default)
			)
			(layer "B.SilkS")
		)
		(fp_line
			(start 1.143 0.5588)
			(end -1.143 0.5588)
			(stroke
				(width 0.1)
				(type default)
			)
			(layer "B.SilkS")
		)
		(fp_rect
			(start -1.143 -0.5588)
			(end 1.143 0.5588)
			(stroke
				(width 0)
				(type default)
			)
			(fill no)
			(layer "B.CrtYd")
		)
		(fp_line
			(start -0.508 -0.3048)
			(end 0.508 -0.3048)
			(stroke
				(width 0.1)
				(type default)
			)
			(layer "B.Fab")
		)
		(fp_line
			(start -0.508 0.3048)
			(end -0.508 -0.3048)
			(stroke
				(width 0.1)
				(type default)
			)
			(layer "B.Fab")
		)
		(fp_line
			(start 0.508 -0.3048)
			(end 0.508 0.3048)
			(stroke
				(width 0.1)
				(type default)
			)
			(layer "B.Fab")
		)
		(fp_line
			(start 0.508 0.3048)
			(end -0.508 0.3048)
			(stroke
				(width 0.1)
				(type default)
			)
			(layer "B.Fab")
		)
		(pad "1" smd rect
			(at 0.5334 0 180)
			(size 0.7112 0.6096)
			(layers "B.Cu" "B.Mask" "B.Paste")
			(net "XP3R3V_FPGA")
		)
		(pad "2" smd rect
			(at -0.5334 0 180)
			(size 0.7112 0.6096)
			(layers "B.Cu" "B.Mask" "B.Paste")
			(net "BNO080_I2C_SCL")
		)
		(zone
			(layer "B.Cu")
			(hatch none 0.5)
			(connect_pads
				(clearance 0)
			)
			(min_thickness 0.25)
			(keepout
				(tracks allowed)
				(vias not_allowed)
				(pads allowed)
				(copperpour not_allowed)
				(footprints allowed)
			)
			(placement
				(enabled no)
				(sheetname "")
			)
			(fill
				(thermal_gap 0.5)
				(thermal_bridge_width 0.5)
				(island_removal_mode 0)
			)
			(polygon
				(pts
					(xy 85.0138 -57.5818) (xy 85.0138 -56.9722) (xy 85.1662 -56.9722) (xy 85.1662 -57.5818)
				)
			)
		)
	)
	(footprint ""
		(layer "B.Cu")
		(at 34.544 -82.169 180)
		(property "Reference" "R349"
			(at 0.381 2.37363 0)
			(unlocked yes)
			(layer "B.SilkS")
			(effects
				(font
					(size 0.7874 0.5842)
					(thickness 0.1524)
				)
				(justify mirror)
			)
		)
		(property "Value" "VAL*"
			(at -0.02032 2.13233 180)
			(unlocked yes)
			(layer "B.Fab")
			(hide yes)
			(effects
				(font
					(size 0.7874 0.5842)
					(thickness 0.1524)
				)
				(justify mirror)
			)
		)
		(property "Tolerance" "TOL*"
			(at -0.044704 3.05435 180)
			(unlocked yes)
			(layer "Cmts.User")
			(hide yes)
			(effects
				(font
					(size 0.7874 0.5842)
					(thickness 0.1524)
				)
				(justify mirror)
			)
		)
		(property "User Part Number" "PARTNUM*"
			(at -0.02032 4.024884 180)
			(unlocked yes)
			(layer "Cmts.User")
			(hide yes)
			(effects
				(font
					(size 0.7874 0.5842)
					(thickness 0.1524)
				)
				(justify mirror)
			)
		)
		(property "Device Type" "RESISTOR-G155-11003-01,100KOHMA"
			(at -0.008382 1.210564 180)
			(unlocked yes)
			(layer "B.Fab")
			(hide yes)
			(effects
				(font
					(size 0.7874 0.5842)
					(thickness 0.1524)
				)
				(justify mirror)
			)
		)
		(duplicate_pad_numbers_are_jumpers no)
		(fp_line
			(start 1.143 0.5588)
			(end -1.143 0.5588)
			(stroke
				(width 0.1)
				(type default)
			)
			(layer "B.SilkS")
		)
		(fp_line
			(start 1.143 -0.5588)
			(end 1.143 0.5588)
			(stroke
				(width 0.1)
				(type default)
			)
			(layer "B.SilkS")
		)
		(fp_line
			(start -1.143 0.5588)
			(end -1.143 -0.5588)
			(stroke
				(width 0.1)
				(type default)
			)
			(layer "B.SilkS")
		)
		(fp_line
			(start -1.143 -0.5588)
			(end 1.143 -0.5588)
			(stroke
				(width 0.1)
				(type default)
			)
			(layer "B.SilkS")
		)
		(fp_rect
			(start 1.143 0.5588)
			(end -1.143 -0.5588)
			(stroke
				(width 0)
				(type default)
			)
			(fill no)
			(layer "B.CrtYd")
		)
		(fp_line
			(start 0.508 0.3048)
			(end -0.508 0.3048)
			(stroke
				(width 0.1)
				(type default)
			)
			(layer "B.Fab")
		)
		(fp_line
			(start 0.508 -0.3048)
			(end 0.508 0.3048)
			(stroke
				(width 0.1)
				(type default)
			)
			(layer "B.Fab")
		)
		(fp_line
			(start -0.508 0.3048)
			(end -0.508 -0.3048)
			(stroke
				(width 0.1)
				(type default)
			)
			(layer "B.Fab")
		)
		(fp_line
			(start -0.508 -0.3048)
			(end 0.508 -0.3048)
			(stroke
				(width 0.1)
				(type default)
			)
			(layer "B.Fab")
		)
		(pad "1" smd rect
			(at 0.5334 0)
			(size 0.7112 0.6096)
			(layers "B.Cu" "B.Mask" "B.Paste")
			(net "R_FT4232_CHD_RX")
		)
		(pad "2" smd rect
			(at -0.5334 0)
			(size 0.7112 0.6096)
			(layers "B.Cu" "B.Mask" "B.Paste")
			(net "XP3R3V_FT4232")
		)
		(zone
			(layer "B.Cu")
			(hatch none 0.5)
			(connect_pads
				(clearance 0)
			)
			(min_thickness 0.25)
			(keepout
				(tracks allowed)
				(vias not_allowed)
				(pads allowed)
				(copperpour not_allowed)
				(footprints allowed)
			)
			(placement
				(enabled no)
				(sheetname "")
			)
			(fill
				(thermal_gap 0.5)
				(thermal_bridge_width 0.5)
				(island_removal_mode 0)
			)
			(polygon
				(pts
					(xy 34.4678 -82.4738) (xy 34.4678 -81.8642) (xy 34.6202 -81.8642) (xy 34.6202 -82.4738)
				)
			)
		)
		(zone
			(layer "B.Cu")
			(hatch none 0.5)
			(connect_pads
				(clearance 0)
			)
			(min_thickness 0.25)
			(keepout
				(tracks not_allowed)
				(vias allowed)
				(pads allowed)
				(copperpour not_allowed)
				(footprints allowed)
			)
			(placement
				(enabled no)
				(sheetname "")
			)
			(fill
				(thermal_gap 0.5)
				(thermal_bridge_width 0.5)
				(island_removal_mode 0)
			)
			(polygon
				(pts
					(xy 34.4678 -82.4738) (xy 34.4678 -81.8642) (xy 34.6202 -81.8642) (xy 34.6202 -82.4738)
				)
			)
		)
	)
)
